(kicad_pcb
	(version 20260206)
	(generator "pcbnew")
	(generator_version "10.0")
	(general
		(thickness 1.6)
		(legacy_teardrops no)
	)
	(paper "A4")
	(title_block
		(title "04192023_DAF0TMB3IC0_F0TG_MB_C_brd_V02_OCP.brd")
		(comment 1 "Grand Teton / footprints 5958-5963 of 8354")
	)
	(layers
		(0 "F.Cu" signal "TOP")
		(4 "In1.Cu" signal "GND")
		(6 "In2.Cu" signal "IN1")
		(8 "In3.Cu" signal "GND1")
		(10 "In4.Cu" signal "IN2")
		(12 "In5.Cu" signal "GND2")
		(14 "In6.Cu" signal "IN3")
		(16 "In7.Cu" signal "GND3")
		(18 "In8.Cu" signal "VCC")
		(20 "In9.Cu" signal "VCC1")
		(22 "In10.Cu" signal "GND4")
		(24 "In11.Cu" signal "IN4")
		(26 "In12.Cu" signal "GND5")
		(28 "In13.Cu" signal "IN5")
		(30 "In14.Cu" signal "GND6")
		(32 "In15.Cu" signal "IN6")
		(34 "In16.Cu" signal "GND7")
		(2 "B.Cu" signal "BOTTOM")
		(9 "F.Adhes" user "F.Adhesive")
		(11 "B.Adhes" user "B.Adhesive")
		(13 "F.Paste" user "Package Geometry/Pastemask Top")
		(15 "B.Paste" user "Package Geometry/Pastemask Bottom")
		(5 "F.SilkS" user "Ref Des/Silkscreen Top")
		(7 "B.SilkS" user "Ref Des/Silkscreen Bottom")
		(1 "F.Mask" user "Board Geometry/Soldermask Top")
		(3 "B.Mask" user "Board Geometry/Soldermask Bottom")
		(17 "Dwgs.User" user "User.Drawings")
		(19 "Cmts.User" user "User.Comments")
		(21 "Eco1.User" user "User.Eco1")
		(23 "Eco2.User" user "User.Eco2")
		(25 "Edge.Cuts" user "Board Geometry/Outline")
		(27 "Margin" user)
		(31 "F.CrtYd" user "Package Geometry/Place Bound Top")
		(29 "B.CrtYd" user "Package Geometry/Place Bound Bottom")
		(35 "F.Fab" user "Ref Des/Assembly Top")
		(33 "B.Fab" user "Ref Des/Assembly Bottom")
	)
	(footprint ""
		(layer "B.Cu")
		(at 163.886388 -13.65504 90)
		(property "Reference" "R2424"
			(at 0 0 90)
			(layer "B.SilkS")
			(hide yes)
			(effects
				(font
					(size 1.27 1.27)
				)
				(justify mirror)
			)
		)
		(property "Value" ""
			(at 0 0 90)
			(layer "B.Fab")
			(effects
				(font
					(size 1.27 1.27)
				)
				(justify mirror)
			)
		)
		(duplicate_pad_numbers_are_jumpers no)
		(fp_line
			(start 0.7874 -0.4064)
			(end -0.7874 -0.4064)
			(stroke
				(width 0.1524)
				(type default)
			)
			(layer "B.SilkS")
		)
		(fp_line
			(start -0.7874 -0.4064)
			(end -0.7874 0.4064)
			(stroke
				(width 0.1524)
				(type default)
			)
			(layer "B.SilkS")
		)
		(fp_line
			(start 0.7874 0.4064)
			(end 0.7874 -0.4064)
			(stroke
				(width 0.1524)
				(type default)
			)
			(layer "B.SilkS")
		)
		(fp_line
			(start -0.7874 0.4064)
			(end 0.7874 0.4064)
			(stroke
				(width 0.1524)
				(type default)
			)
			(layer "B.SilkS")
		)
		(fp_line
			(start 0.67945 -0.305054)
			(end 0.12065 -0.305054)
			(stroke
				(width 0.1)
				(type default)
			)
			(layer "B.Fab")
		)
		(fp_line
			(start 0.12065 -0.305054)
			(end 0.12065 -0.2794)
			(stroke
				(width 0.1)
				(type default)
			)
			(layer "B.Fab")
		)
		(fp_line
			(start -0.12065 -0.3048)
			(end -0.67945 -0.3048)
			(stroke
				(width 0.1)
				(type default)
			)
			(layer "B.Fab")
		)
		(fp_line
			(start -0.67945 -0.3048)
			(end -0.67945 0.3048)
			(stroke
				(width 0.1)
				(type default)
			)
			(layer "B.Fab")
		)
		(fp_line
			(start 0.12065 -0.2794)
			(end -0.12065 -0.2794)
			(stroke
				(width 0.1)
				(type default)
			)
			(layer "B.Fab")
		)
		(fp_line
			(start -0.12065 -0.2794)
			(end -0.12065 -0.3048)
			(stroke
				(width 0.1)
				(type default)
			)
			(layer "B.Fab")
		)
		(fp_line
			(start 0.12065 0.2794)
			(end 0.12065 0.3048)
			(stroke
				(width 0.1)
				(type default)
			)
			(layer "B.Fab")
		)
		(fp_line
			(start -0.120396 0.2794)
			(end 0.12065 0.2794)
			(stroke
				(width 0.1)
				(type default)
			)
			(layer "B.Fab")
		)
		(fp_line
			(start 0.67945 0.3048)
			(end 0.67945 -0.305054)
			(stroke
				(width 0.1)
				(type default)
			)
			(layer "B.Fab")
		)
		(fp_line
			(start 0.12065 0.3048)
			(end 0.67945 0.3048)
			(stroke
				(width 0.1)
				(type default)
			)
			(layer "B.Fab")
		)
		(fp_line
			(start -0.120396 0.3048)
			(end -0.120396 0.2794)
			(stroke
				(width 0.1)
				(type default)
			)
			(layer "B.Fab")
		)
		(fp_line
			(start -0.67945 0.3048)
			(end -0.120396 0.3048)
			(stroke
				(width 0.1)
				(type default)
			)
			(layer "B.Fab")
		)
		(pad "1" smd circle
			(at 0.40005 0 270)
			(size 0 0)
			(layers "B.Cu" "B.Mask" "B.Paste")
			(net "SMB_PMBUS_3V3AUX_SDA")
		)
		(pad "2" smd circle
			(at -0.40005 0 270)
			(size 0 0)
			(layers "B.Cu" "B.Mask" "B.Paste")
			(net "SMB_PMBUS_3V3AUX_SDA_R0")
		)
	)
	(footprint ""
		(layer "B.Cu")
		(at 233.68 -330.708 180)
		(property "Reference" "R6785"
			(at 0 0 0)
			(layer "B.SilkS")
			(hide yes)
			(effects
				(font
					(size 1.27 1.27)
				)
				(justify mirror)
			)
		)
		(property "Value" ""
			(at 0 0 0)
			(layer "B.Fab")
			(effects
				(font
					(size 1.27 1.27)
				)
				(justify mirror)
			)
		)
		(duplicate_pad_numbers_are_jumpers no)
		(fp_line
			(start 0.7874 0.4064)
			(end 0.7874 -0.4064)
			(stroke
				(width 0.1524)
				(type default)
			)
			(layer "B.SilkS")
		)
		(fp_line
			(start 0.7874 -0.4064)
			(end -0.7874 -0.4064)
			(stroke
				(width 0.1524)
				(type default)
			)
			(layer "B.SilkS")
		)
		(fp_line
			(start -0.7874 0.4064)
			(end 0.7874 0.4064)
			(stroke
				(width 0.1524)
				(type default)
			)
			(layer "B.SilkS")
		)
		(fp_line
			(start -0.7874 -0.4064)
			(end -0.7874 0.4064)
			(stroke
				(width 0.1524)
				(type default)
			)
			(layer "B.SilkS")
		)
		(fp_line
			(start 0.67945 0.3048)
			(end 0.67945 -0.305054)
			(stroke
				(width 0.1)
				(type default)
			)
			(layer "B.Fab")
		)
		(fp_line
			(start 0.67945 -0.305054)
			(end 0.12065 -0.305054)
			(stroke
				(width 0.1)
				(type default)
			)
			(layer "B.Fab")
		)
		(fp_line
			(start 0.12065 0.3048)
			(end 0.67945 0.3048)
			(stroke
				(width 0.1)
				(type default)
			)
			(layer "B.Fab")
		)
		(fp_line
			(start 0.12065 0.2794)
			(end 0.12065 0.3048)
			(stroke
				(width 0.1)
				(type default)
			)
			(layer "B.Fab")
		)
		(fp_line
			(start 0.12065 -0.2794)
			(end -0.12065 -0.2794)
			(stroke
				(width 0.1)
				(type default)
			)
			(layer "B.Fab")
		)
		(fp_line
			(start 0.12065 -0.305054)
			(end 0.12065 -0.2794)
			(stroke
				(width 0.1)
				(type default)
			)
			(layer "B.Fab")
		)
		(fp_line
			(start -0.120396 0.3048)
			(end -0.120396 0.2794)
			(stroke
				(width 0.1)
				(type default)
			)
			(layer "B.Fab")
		)
		(fp_line
			(start -0.120396 0.2794)
			(end 0.12065 0.2794)
			(stroke
				(width 0.1)
				(type default)
			)
			(layer "B.Fab")
		)
		(fp_line
			(start -0.12065 -0.2794)
			(end -0.12065 -0.3048)
			(stroke
				(width 0.1)
				(type default)
			)
			(layer "B.Fab")
		)
		(fp_line
			(start -0.12065 -0.3048)
			(end -0.67945 -0.3048)
			(stroke
				(width 0.1)
				(type default)
			)
			(layer "B.Fab")
		)
		(fp_line
			(start -0.67945 0.3048)
			(end -0.120396 0.3048)
			(stroke
				(width 0.1)
				(type default)
			)
			(layer "B.Fab")
		)
		(fp_line
			(start -0.67945 -0.3048)
			(end -0.67945 0.3048)
			(stroke
				(width 0.1)
				(type default)
			)
			(layer "B.Fab")
		)
		(pad "1" smd circle
			(at 0.40005 0)
			(size 0 0)
			(layers "B.Cu" "B.Mask" "B.Paste")
			(net "SMB_MUX_RT_R1_SDA")
		)
		(pad "2" smd circle
			(at -0.40005 0)
			(size 0 0)
			(layers "B.Cu" "B.Mask" "B.Paste")
			(net "SMB_SML1_PMBUS_HSC_SDA")
		)
	)
	(footprint ""
		(layer "B.Cu")
		(at 396.157958 -313.477148 180)
		(property "Reference" "R432"
			(at 0 0 0)
			(layer "B.SilkS")
			(hide yes)
			(effects
				(font
					(size 1.27 1.27)
				)
				(justify mirror)
			)
		)
		(property "Value" ""
			(at 0 0 0)
			(layer "B.Fab")
			(effects
				(font
					(size 1.27 1.27)
				)
				(justify mirror)
			)
		)
		(duplicate_pad_numbers_are_jumpers no)
		(fp_line
			(start 0.7874 0.4064)
			(end 0.7874 -0.4064)
			(stroke
				(width 0.1524)
				(type default)
			)
			(layer "B.SilkS")
		)
		(fp_line
			(start 0.7874 -0.4064)
			(end -0.7874 -0.4064)
			(stroke
				(width 0.1524)
				(type default)
			)
			(layer "B.SilkS")
		)
		(fp_line
			(start -0.7874 0.4064)
			(end 0.7874 0.4064)
			(stroke
				(width 0.1524)
				(type default)
			)
			(layer "B.SilkS")
		)
		(fp_line
			(start -0.7874 -0.4064)
			(end -0.7874 0.4064)
			(stroke
				(width 0.1524)
				(type default)
			)
			(layer "B.SilkS")
		)
		(fp_line
			(start 0.67945 0.3048)
			(end 0.67945 -0.305054)
			(stroke
				(width 0.1)
				(type default)
			)
			(layer "B.Fab")
		)
		(fp_line
			(start 0.67945 -0.305054)
			(end 0.12065 -0.305054)
			(stroke
				(width 0.1)
				(type default)
			)
			(layer "B.Fab")
		)
		(fp_line
			(start 0.12065 0.3048)
			(end 0.67945 0.3048)
			(stroke
				(width 0.1)
				(type default)
			)
			(layer "B.Fab")
		)
		(fp_line
			(start 0.12065 0.2794)
			(end 0.12065 0.3048)
			(stroke
				(width 0.1)
				(type default)
			)
			(layer "B.Fab")
		)
		(fp_line
			(start 0.12065 -0.2794)
			(end -0.12065 -0.2794)
			(stroke
				(width 0.1)
				(type default)
			)
			(layer "B.Fab")
		)
		(fp_line
			(start 0.12065 -0.305054)
			(end 0.12065 -0.2794)
			(stroke
				(width 0.1)
				(type default)
			)
			(layer "B.Fab")
		)
		(fp_line
			(start -0.120396 0.3048)
			(end -0.120396 0.2794)
			(stroke
				(width 0.1)
				(type default)
			)
			(layer "B.Fab")
		)
		(fp_line
			(start -0.120396 0.2794)
			(end 0.12065 0.2794)
			(stroke
				(width 0.1)
				(type default)
			)
			(layer "B.Fab")
		)
		(fp_line
			(start -0.12065 -0.2794)
			(end -0.12065 -0.3048)
			(stroke
				(width 0.1)
				(type default)
			)
			(layer "B.Fab")
		)
		(fp_line
			(start -0.12065 -0.3048)
			(end -0.67945 -0.3048)
			(stroke
				(width 0.1)
				(type default)
			)
			(layer "B.Fab")
		)
		(fp_line
			(start -0.67945 0.3048)
			(end -0.120396 0.3048)
			(stroke
				(width 0.1)
				(type default)
			)
			(layer "B.Fab")
		)
		(fp_line
			(start -0.67945 -0.3048)
			(end -0.67945 0.3048)
			(stroke
				(width 0.1)
				(type default)
			)
			(layer "B.Fab")
		)
		(pad "1" smd circle
			(at 0.40005 0)
			(size 0 0)
			(layers "B.Cu" "B.Mask" "B.Paste")
			(net "XTAL_CPU0_X48M_X1")
		)
		(pad "2" smd circle
			(at -0.40005 0)
			(size 0 0)
			(layers "B.Cu" "B.Mask" "B.Paste")
			(net "XTAL_CPU0_X48M_X2_R")
		)
	)
	(footprint ""
		(layer "B.Cu")
		(at 159.383984 -20.056094 90)
		(property "Reference" "R6037"
			(at 0 0 90)
			(layer "B.SilkS")
			(hide yes)
			(effects
				(font
					(size 1.27 1.27)
				)
				(justify mirror)
			)
		)
		(property "Value" ""
			(at 0 0 90)
			(layer "B.Fab")
			(effects
				(font
					(size 1.27 1.27)
				)
				(justify mirror)
			)
		)
		(duplicate_pad_numbers_are_jumpers no)
		(fp_line
			(start 0.7874 -0.4064)
			(end -0.7874 -0.4064)
			(stroke
				(width 0.1524)
				(type default)
			)
			(layer "B.SilkS")
		)
		(fp_line
			(start -0.7874 -0.4064)
			(end -0.7874 0.4064)
			(stroke
				(width 0.1524)
				(type default)
			)
			(layer "B.SilkS")
		)
		(fp_line
			(start 0.7874 0.4064)
			(end 0.7874 -0.4064)
			(stroke
				(width 0.1524)
				(type default)
			)
			(layer "B.SilkS")
		)
		(fp_line
			(start -0.7874 0.4064)
			(end 0.7874 0.4064)
			(stroke
				(width 0.1524)
				(type default)
			)
			(layer "B.SilkS")
		)
		(fp_line
			(start 0.67945 -0.305054)
			(end 0.12065 -0.305054)
			(stroke
				(width 0.1)
				(type default)
			)
			(layer "B.Fab")
		)
		(fp_line
			(start 0.12065 -0.305054)
			(end 0.12065 -0.2794)
			(stroke
				(width 0.1)
				(type default)
			)
			(layer "B.Fab")
		)
		(fp_line
			(start -0.12065 -0.3048)
			(end -0.67945 -0.3048)
			(stroke
				(width 0.1)
				(type default)
			)
			(layer "B.Fab")
		)
		(fp_line
			(start -0.67945 -0.3048)
			(end -0.67945 0.3048)
			(stroke
				(width 0.1)
				(type default)
			)
			(layer "B.Fab")
		)
		(fp_line
			(start 0.12065 -0.2794)
			(end -0.12065 -0.2794)
			(stroke
				(width 0.1)
				(type default)
			)
			(layer "B.Fab")
		)
		(fp_line
			(start -0.12065 -0.2794)
			(end -0.12065 -0.3048)
			(stroke
				(width 0.1)
				(type default)
			)
			(layer "B.Fab")
		)
		(fp_line
			(start 0.12065 0.2794)
			(end 0.12065 0.3048)
			(stroke
				(width 0.1)
				(type default)
			)
			(layer "B.Fab")
		)
		(fp_line
			(start -0.120396 0.2794)
			(end 0.12065 0.2794)
			(stroke
				(width 0.1)
				(type default)
			)
			(layer "B.Fab")
		)
		(fp_line
			(start 0.67945 0.3048)
			(end 0.67945 -0.305054)
			(stroke
				(width 0.1)
				(type default)
			)
			(layer "B.Fab")
		)
		(fp_line
			(start 0.12065 0.3048)
			(end 0.67945 0.3048)
			(stroke
				(width 0.1)
				(type default)
			)
			(layer "B.Fab")
		)
		(fp_line
			(start -0.120396 0.3048)
			(end -0.120396 0.2794)
			(stroke
				(width 0.1)
				(type default)
			)
			(layer "B.Fab")
		)
		(fp_line
			(start -0.67945 0.3048)
			(end -0.120396 0.3048)
			(stroke
				(width 0.1)
				(type default)
			)
			(layer "B.Fab")
		)
		(pad "1" smd circle
			(at 0.40005 0 270)
			(size 0 0)
			(layers "B.Cu" "B.Mask" "B.Paste")
			(net "SMB_1_PLD_3V3AUX_SDA")
		)
		(pad "2" smd circle
			(at -0.40005 0 270)
			(size 0 0)
			(layers "B.Cu" "B.Mask" "B.Paste")
			(net "P3V3_AUX")
		)
	)
	(footprint ""
		(layer "B.Cu")
		(at 73.841864 -11.26871 90)
		(property "Reference" "R3176"
			(at 0 0 90)
			(layer "B.SilkS")
			(hide yes)
			(effects
				(font
					(size 1.27 1.27)
				)
				(justify mirror)
			)
		)
		(property "Value" ""
			(at 0 0 90)
			(layer "B.Fab")
			(effects
				(font
					(size 1.27 1.27)
				)
				(justify mirror)
			)
		)
		(duplicate_pad_numbers_are_jumpers no)
		(fp_line
			(start 0.7874 -0.4064)
			(end -0.7874 -0.4064)
			(stroke
				(width 0.1524)
				(type default)
			)
			(layer "B.SilkS")
		)
		(fp_line
			(start -0.7874 -0.4064)
			(end -0.7874 0.4064)
			(stroke
				(width 0.1524)
				(type default)
			)
			(layer "B.SilkS")
		)
		(fp_line
			(start 0.7874 0.4064)
			(end 0.7874 -0.4064)
			(stroke
				(width 0.1524)
				(type default)
			)
			(layer "B.SilkS")
		)
		(fp_line
			(start -0.7874 0.4064)
			(end 0.7874 0.4064)
			(stroke
				(width 0.1524)
				(type default)
			)
			(layer "B.SilkS")
		)
		(fp_line
			(start 0.67945 -0.305054)
			(end 0.12065 -0.305054)
			(stroke
				(width 0.1)
				(type default)
			)
			(layer "B.Fab")
		)
		(fp_line
			(start 0.12065 -0.305054)
			(end 0.12065 -0.2794)
			(stroke
				(width 0.1)
				(type default)
			)
			(layer "B.Fab")
		)
		(fp_line
			(start -0.12065 -0.3048)
			(end -0.67945 -0.3048)
			(stroke
				(width 0.1)
				(type default)
			)
			(layer "B.Fab")
		)
		(fp_line
			(start -0.67945 -0.3048)
			(end -0.67945 0.3048)
			(stroke
				(width 0.1)
				(type default)
			)
			(layer "B.Fab")
		)
		(fp_line
			(start 0.12065 -0.2794)
			(end -0.12065 -0.2794)
			(stroke
				(width 0.1)
				(type default)
			)
			(layer "B.Fab")
		)
		(fp_line
			(start -0.12065 -0.2794)
			(end -0.12065 -0.3048)
			(stroke
				(width 0.1)
				(type default)
			)
			(layer "B.Fab")
		)
		(fp_line
			(start 0.12065 0.2794)
			(end 0.12065 0.3048)
			(stroke
				(width 0.1)
				(type default)
			)
			(layer "B.Fab")
		)
		(fp_line
			(start -0.120396 0.2794)
			(end 0.12065 0.2794)
			(stroke
				(width 0.1)
				(type default)
			)
			(layer "B.Fab")
		)
		(fp_line
			(start 0.67945 0.3048)
			(end 0.67945 -0.305054)
			(stroke
				(width 0.1)
				(type default)
			)
			(layer "B.Fab")
		)
		(fp_line
			(start 0.12065 0.3048)
			(end 0.67945 0.3048)
			(stroke
				(width 0.1)
				(type default)
			)
			(layer "B.Fab")
		)
		(fp_line
			(start -0.120396 0.3048)
			(end -0.120396 0.2794)
			(stroke
				(width 0.1)
				(type default)
			)
			(layer "B.Fab")
		)
		(fp_line
			(start -0.67945 0.3048)
			(end -0.120396 0.3048)
			(stroke
				(width 0.1)
				(type default)
			)
			(layer "B.Fab")
		)
		(pad "1" smd circle
			(at 0.40005 0 270)
			(size 0 0)
			(layers "B.Cu" "B.Mask" "B.Paste")
			(net "SGPIO_OCP_V3_2_CLK")
		)
		(pad "2" smd circle
			(at -0.40005 0 270)
			(size 0 0)
			(layers "B.Cu" "B.Mask" "B.Paste")
			(net "P3V3_OCP_V3_2")
		)
	)
	(footprint ""
		(layer "B.Cu")
		(at 58.3184 -388.011162 -90)
		(property "Reference" "C130"
			(at 0 0 90)
			(layer "B.SilkS")
			(hide yes)
			(effects
				(font
					(size 1.27 1.27)
				)
				(justify mirror)
			)
		)
		(property "Value" ""
			(at 0 0 90)
			(layer "B.Fab")
			(effects
				(font
					(size 1.27 1.27)
				)
				(justify mirror)
			)
		)
		(duplicate_pad_numbers_are_jumpers no)
		(fp_line
			(start -0.299974 0.150114)
			(end 0.299974 0.150114)
			(stroke
				(width 0.1)
				(type default)
			)
			(layer "B.Fab")
		)
		(fp_line
			(start 0.299974 0.150114)
			(end 0.299974 -0.150114)
			(stroke
				(width 0.1)
				(type default)
			)
			(layer "B.Fab")
		)
		(fp_line
			(start -0.299974 -0.150114)
			(end -0.299974 0.150114)
			(stroke
				(width 0.1)
				(type default)
			)
			(layer "B.Fab")
		)
		(fp_line
			(start 0.299974 -0.150114)
			(end -0.299974 -0.150114)
			(stroke
				(width 0.1)
				(type default)
			)
			(layer "B.Fab")
		)
		(pad "1" smd rect
			(at 0.2667 0 90)
			(size 0.3048 0.381)
			(layers "B.Cu" "B.Mask" "B.Paste")
			(net "P1V8_CPU1_RT0_1A_1D")
		)
		(pad "2" smd rect
			(at -0.2667 0 90)
			(size 0.3048 0.381)
			(layers "B.Cu" "B.Mask" "B.Paste")
			(net "GND")
		)
	)
)
